(kicad_pcb
	(version 20260206)
	(generator "pcbnew")
	(generator_version "10.0")
	(general
		(thickness 1.6)
		(legacy_teardrops no)
	)
	(paper "A4")
	(title_block
		(title "01162023_DA0F0TEBIF0_F0T_Expander_BD_F_brd_V02_OCP.brd")
		(comment 1 "Grand Teton / footprints 2762-2766 of 9728")
	)
	(layers
		(0 "F.Cu" signal "TOP")
		(4 "In1.Cu" signal "GND")
		(6 "In2.Cu" signal "VCC")
		(8 "In3.Cu" signal "VCC1")
		(10 "In4.Cu" signal "GND1")
		(12 "In5.Cu" signal "IN1")
		(14 "In6.Cu" signal "GND2")
		(16 "In7.Cu" signal "IN2")
		(18 "In8.Cu" signal "GND3")
		(20 "In9.Cu" signal "IN3")
		(22 "In10.Cu" signal "GND4")
		(24 "In11.Cu" signal "IN4")
		(26 "In12.Cu" signal "GND5")
		(28 "In13.Cu" signal "IN5")
		(30 "In14.Cu" signal "GND6")
		(32 "In15.Cu" signal "IN6")
		(34 "In16.Cu" signal "GND7")
		(2 "B.Cu" signal "BOTTOM")
		(9 "F.Adhes" user "F.Adhesive")
		(11 "B.Adhes" user "B.Adhesive")
		(13 "F.Paste" user "Package Geometry/Pastemask Top")
		(15 "B.Paste" user "Package Geometry/Pastemask Bottom")
		(5 "F.SilkS" user "Ref Des/Silkscreen Top")
		(7 "B.SilkS" user "Ref Des/Silkscreen Bottom")
		(1 "F.Mask" user "Board Geometry/Soldermask Top")
		(3 "B.Mask" user "Board Geometry/Soldermask Bottom")
		(17 "Dwgs.User" user "User.Drawings")
		(19 "Cmts.User" user "User.Comments")
		(21 "Eco1.User" user "User.Eco1")
		(23 "Eco2.User" user "User.Eco2")
		(25 "Edge.Cuts" user "Board Geometry/Outline")
		(27 "Margin" user)
		(31 "F.CrtYd" user "Package Geometry/Place Bound Top")
		(29 "B.CrtYd" user "Package Geometry/Place Bound Bottom")
		(35 "F.Fab" user "Ref Des/Assembly Top")
		(33 "B.Fab" user "Ref Des/Assembly Bottom")
	)
	(footprint ""
		(layer "F.Cu")
		(at 361.329478 -280.44902 -90)
		(property "Reference" "PC195"
			(at 0 0 270)
			(layer "F.SilkS")
			(hide yes)
			(effects
				(font
					(size 1.27 1.27)
				)
			)
		)
		(property "Value" ""
			(at 0 0 270)
			(layer "F.Fab")
			(effects
				(font
					(size 1.27 1.27)
				)
			)
		)
		(duplicate_pad_numbers_are_jumpers no)
		(fp_line
			(start -0.7874 0.4064)
			(end -0.7874 -0.4064)
			(stroke
				(width 0.1524)
				(type default)
			)
			(layer "F.SilkS")
		)
		(fp_line
			(start 0.7874 0.4064)
			(end -0.7874 0.4064)
			(stroke
				(width 0.1524)
				(type default)
			)
			(layer "F.SilkS")
		)
		(fp_line
			(start -0.7874 -0.4064)
			(end 0.7874 -0.4064)
			(stroke
				(width 0.1524)
				(type default)
			)
			(layer "F.SilkS")
		)
		(fp_line
			(start 0.7874 -0.4064)
			(end 0.7874 0.4064)
			(stroke
				(width 0.1524)
				(type default)
			)
			(layer "F.SilkS")
		)
		(fp_line
			(start -0.67945 0.3048)
			(end -0.67945 -0.305054)
			(stroke
				(width 0.1)
				(type default)
			)
			(layer "F.Fab")
		)
		(fp_line
			(start -0.12065 0.3048)
			(end -0.67945 0.3048)
			(stroke
				(width 0.1)
				(type default)
			)
			(layer "F.Fab")
		)
		(fp_line
			(start 0.120396 0.3048)
			(end 0.120396 0.2794)
			(stroke
				(width 0.1)
				(type default)
			)
			(layer "F.Fab")
		)
		(fp_line
			(start 0.67945 0.3048)
			(end 0.120396 0.3048)
			(stroke
				(width 0.1)
				(type default)
			)
			(layer "F.Fab")
		)
		(fp_line
			(start -0.12065 0.2794)
			(end -0.12065 0.3048)
			(stroke
				(width 0.1)
				(type default)
			)
			(layer "F.Fab")
		)
		(fp_line
			(start 0.120396 0.2794)
			(end -0.12065 0.2794)
			(stroke
				(width 0.1)
				(type default)
			)
			(layer "F.Fab")
		)
		(fp_line
			(start -0.12065 -0.2794)
			(end 0.12065 -0.2794)
			(stroke
				(width 0.1)
				(type default)
			)
			(layer "F.Fab")
		)
		(fp_line
			(start 0.12065 -0.2794)
			(end 0.12065 -0.3048)
			(stroke
				(width 0.1)
				(type default)
			)
			(layer "F.Fab")
		)
		(fp_line
			(start 0.12065 -0.3048)
			(end 0.67945 -0.3048)
			(stroke
				(width 0.1)
				(type default)
			)
			(layer "F.Fab")
		)
		(fp_line
			(start 0.67945 -0.3048)
			(end 0.67945 0.3048)
			(stroke
				(width 0.1)
				(type default)
			)
			(layer "F.Fab")
		)
		(fp_line
			(start -0.67945 -0.305054)
			(end -0.12065 -0.305054)
			(stroke
				(width 0.1)
				(type default)
			)
			(layer "F.Fab")
		)
		(fp_line
			(start -0.12065 -0.305054)
			(end -0.12065 -0.2794)
			(stroke
				(width 0.1)
				(type default)
			)
			(layer "F.Fab")
		)
		(pad "1" smd circle
			(at -0.40005 0 270)
			(size 0 0)
			(layers "F.Cu" "F.Mask" "F.Paste")
			(net "SW_P0V8_PEX3_PHASE2")
		)
		(pad "2" smd circle
			(at 0.40005 0 270)
			(size 0 0)
			(layers "F.Cu" "F.Mask" "F.Paste")
			(net "SW_P0V8_PEX3_BOOT2_R")
		)
	)
	(footprint ""
		(layer "F.Cu")
		(at 295.881044 -202.518772 -90)
		(property "Reference" "U63"
			(at 1.045972 -3.433826 90)
			(unlocked yes)
			(layer "F.SilkS")
			(effects
				(font
					(size 0.7874 0.5842)
					(thickness 0.1524)
				)
				(justify left)
			)
		)
		(property "Value" ""
			(at 0 0 270)
			(layer "F.Fab")
			(effects
				(font
					(size 1.27 1.27)
				)
			)
		)
		(duplicate_pad_numbers_are_jumpers no)
		(fp_line
			(start -1.868932 2.549906)
			(end 1.868932 2.549906)
			(stroke
				(width 0.1524)
				(type default)
			)
			(layer "F.SilkS")
		)
		(fp_line
			(start 1.868932 2.549906)
			(end 1.868932 -2.549906)
			(stroke
				(width 0.1524)
				(type default)
			)
			(layer "F.SilkS")
		)
		(fp_line
			(start 0 -1.524)
			(end -1.025906 -2.549906)
			(stroke
				(width 0.1524)
				(type default)
			)
			(layer "F.SilkS")
		)
		(fp_line
			(start -1.868932 -2.549906)
			(end -1.868932 2.549906)
			(stroke
				(width 0.1524)
				(type default)
			)
			(layer "F.SilkS")
		)
		(fp_line
			(start -1.025906 -2.549906)
			(end -1.868932 -2.549906)
			(stroke
				(width 0.1524)
				(type default)
			)
			(layer "F.SilkS")
		)
		(fp_line
			(start 1.025906 -2.549906)
			(end 0 -1.524)
			(stroke
				(width 0.1524)
				(type default)
			)
			(layer "F.SilkS")
		)
		(fp_line
			(start 1.868932 -2.549906)
			(end 1.025906 -2.549906)
			(stroke
				(width 0.1524)
				(type default)
			)
			(layer "F.SilkS")
		)
		(fp_poly
			(pts
				(xy -4.7752 -1.787398) (xy -4.7752 -2.803398) (xy -3.7592 -2.295398)
			)
			(stroke
				(width 0)
				(type default)
			)
			(fill yes)
			(layer "F.SilkS")
		)
		(fp_line
			(start -2.249932 2.549906)
			(end 2.249932 2.549906)
			(stroke
				(width 0.1)
				(type default)
			)
			(layer "F.Fab")
		)
		(fp_line
			(start 2.249932 2.549906)
			(end 2.249932 -2.549906)
			(stroke
				(width 0.1)
				(type default)
			)
			(layer "F.Fab")
		)
		(fp_line
			(start -2.249932 -2.549906)
			(end -2.249932 2.549906)
			(stroke
				(width 0.1)
				(type default)
			)
			(layer "F.Fab")
		)
		(fp_line
			(start 2.249932 -2.549906)
			(end -2.249932 -2.549906)
			(stroke
				(width 0.1)
				(type default)
			)
			(layer "F.Fab")
		)
		(fp_poly
			(pts
				(xy -4.7752 -1.787398) (xy -4.7752 -2.803398) (xy -3.7592 -2.295398)
			)
			(stroke
				(width 0)
				(type default)
			)
			(fill yes)
			(layer "F.Fab")
		)
		(pad "1" smd rect
			(at -2.800096 -2.275078 180)
			(size 0.3556 1.6002)
			(layers "F.Cu" "F.Mask" "F.Paste")
			(net "SPI_BIC1_CS0_LS23_N_DIR1")
		)
		(pad "2" smd rect
			(at -2.800096 -1.625092 180)
			(size 0.3556 1.6002)
			(layers "F.Cu" "F.Mask" "F.Paste")
			(net "SPI_BIC1_CLK_LS23_DIR2")
		)
		(pad "3" smd rect
			(at -2.800096 -0.975106 180)
			(size 0.3556 1.6002)
			(layers "F.Cu" "F.Mask" "F.Paste")
			(net "SPI_BIC1_CS0_LS23_N")
		)
		(pad "4" smd rect
			(at -2.800096 -0.32512 180)
			(size 0.3556 1.6002)
			(layers "F.Cu" "F.Mask" "F.Paste")
			(net "SPI_BIC1_CLK_LS23")
		)
		(pad "5" smd rect
			(at -2.800096 0.32512 180)
			(size 0.3556 1.6002)
			(layers "F.Cu" "F.Mask" "F.Paste")
			(net "SPI_BIC1_MOSI_LS23")
		)
		(pad "6" smd rect
			(at -2.800096 0.975106 180)
			(size 0.3556 1.6002)
			(layers "F.Cu" "F.Mask" "F.Paste")
			(net "SPI_BIC1_MISO_LS23")
		)
		(pad "7" smd rect
			(at -2.800096 1.625092 180)
			(size 0.3556 1.6002)
			(layers "F.Cu" "F.Mask" "F.Paste")
			(net "SPI_BIC1_MOSI_LS23_DIR3")
		)
		(pad "8" smd rect
			(at -2.800096 2.275078 180)
			(size 0.3556 1.6002)
			(layers "F.Cu" "F.Mask" "F.Paste")
			(net "SPI_BIC1_MISO_LS23_DIR4")
		)
		(pad "9" smd rect
			(at 2.800096 2.275078 180)
			(size 0.3556 1.6002)
			(layers "F.Cu" "F.Mask" "F.Paste")
			(net "SPI_BIC1_LS23_EN_R_N")
		)
		(pad "10" smd rect
			(at 2.800096 1.625092 180)
			(size 0.3556 1.6002)
			(layers "F.Cu" "F.Mask" "F.Paste")
			(net "GND")
		)
		(pad "11" smd rect
			(at 2.800096 0.975106 180)
			(size 0.3556 1.6002)
			(layers "F.Cu" "F.Mask" "F.Paste")
			(net "SPI_BIC1_MISO_R4")
		)
		(pad "12" smd rect
			(at 2.800096 0.32512 180)
			(size 0.3556 1.6002)
			(layers "F.Cu" "F.Mask" "F.Paste")
			(net "SPI_BIC1_MOSI_R4")
		)
		(pad "13" smd rect
			(at 2.800096 -0.32512 180)
			(size 0.3556 1.6002)
			(layers "F.Cu" "F.Mask" "F.Paste")
			(net "SPI_BIC1_CLK_R4")
		)
		(pad "14" smd rect
			(at 2.800096 -0.975106 180)
			(size 0.3556 1.6002)
			(layers "F.Cu" "F.Mask" "F.Paste")
			(net "SPI_BIC1_CS0_R3_N")
		)
		(pad "15" smd rect
			(at 2.800096 -1.625092 180)
			(size 0.3556 1.6002)
			(layers "F.Cu" "F.Mask" "F.Paste")
			(net "P3V3_AUX")
		)
		(pad "16" smd rect
			(at 2.800096 -2.275078 180)
			(size 0.3556 1.6002)
			(layers "F.Cu" "F.Mask" "F.Paste")
			(net "P1V8_PEX")
		)
	)
	(footprint ""
		(layer "F.Cu")
		(at 222.574866 -254.18542 -90)
		(property "Reference" "C4284"
			(at 0 0 270)
			(layer "F.SilkS")
			(hide yes)
			(effects
				(font
					(size 1.27 1.27)
				)
			)
		)
		(property "Value" ""
			(at 0 0 270)
			(layer "F.Fab")
			(effects
				(font
					(size 1.27 1.27)
				)
			)
		)
		(duplicate_pad_numbers_are_jumpers no)
		(fp_line
			(start -1.2954 0.5842)
			(end -1.2954 -0.5842)
			(stroke
				(width 0.1524)
				(type default)
			)
			(layer "F.SilkS")
		)
		(fp_line
			(start 1.2954 0.5842)
			(end -1.2954 0.5842)
			(stroke
				(width 0.1524)
				(type default)
			)
			(layer "F.SilkS")
		)
		(fp_line
			(start -1.2954 -0.5842)
			(end 1.2954 -0.5842)
			(stroke
				(width 0.1524)
				(type default)
			)
			(layer "F.SilkS")
		)
		(fp_line
			(start 1.2954 -0.5842)
			(end 1.2954 0.5842)
			(stroke
				(width 0.1524)
				(type default)
			)
			(layer "F.SilkS")
		)
		(fp_line
			(start -0.8636 0.4572)
			(end -0.8636 0.4064)
			(stroke
				(width 0.1)
				(type default)
			)
			(layer "F.Fab")
		)
		(fp_line
			(start 0.8636 0.4572)
			(end -0.8636 0.4572)
			(stroke
				(width 0.1)
				(type default)
			)
			(layer "F.Fab")
		)
		(fp_line
			(start -1.1938 0.4064)
			(end -1.1938 -0.4064)
			(stroke
				(width 0.1)
				(type default)
			)
			(layer "F.Fab")
		)
		(fp_line
			(start -0.8636 0.4064)
			(end -1.1938 0.4064)
			(stroke
				(width 0.1)
				(type default)
			)
			(layer "F.Fab")
		)
		(fp_line
			(start 0.8636 0.4064)
			(end 0.8636 0.4572)
			(stroke
				(width 0.1)
				(type default)
			)
			(layer "F.Fab")
		)
		(fp_line
			(start 1.1938 0.4064)
			(end 0.8636 0.4064)
			(stroke
				(width 0.1)
				(type default)
			)
			(layer "F.Fab")
		)
		(fp_line
			(start -1.1938 -0.4064)
			(end -0.8636 -0.4064)
			(stroke
				(width 0.1)
				(type default)
			)
			(layer "F.Fab")
		)
		(fp_line
			(start -0.8636 -0.4064)
			(end -0.8636 -0.4572)
			(stroke
				(width 0.1)
				(type default)
			)
			(layer "F.Fab")
		)
		(fp_line
			(start 0.8636 -0.4064)
			(end 1.1938 -0.4064)
			(stroke
				(width 0.1)
				(type default)
			)
			(layer "F.Fab")
		)
		(fp_line
			(start 1.1938 -0.4064)
			(end 1.1938 0.4064)
			(stroke
				(width 0.1)
				(type default)
			)
			(layer "F.Fab")
		)
		(fp_line
			(start -0.8636 -0.4572)
			(end 0.8636 -0.4572)
			(stroke
				(width 0.1)
				(type default)
			)
			(layer "F.Fab")
		)
		(fp_line
			(start 0.8636 -0.4572)
			(end 0.8636 -0.4064)
			(stroke
				(width 0.1)
				(type default)
			)
			(layer "F.Fab")
		)
		(pad "1" smd rect
			(at -0.7366 0 180)
			(size 0.7112 0.8128)
			(layers "F.Cu" "F.Mask" "F.Paste")
			(net "P1V25_SERDES_VDDPLL_PEX1_C2")
		)
		(pad "2" smd rect
			(at 0.7366 0 180)
			(size 0.7112 0.8128)
			(layers "F.Cu" "F.Mask" "F.Paste")
			(net "GND")
		)
	)
	(footprint ""
		(layer "F.Cu")
		(at 230.749094 -175.70958)
		(property "Reference" "R3150"
			(at 0 0 0)
			(layer "F.SilkS")
			(hide yes)
			(effects
				(font
					(size 1.27 1.27)
				)
			)
		)
		(property "Value" ""
			(at 0 0 0)
			(layer "F.Fab")
			(effects
				(font
					(size 1.27 1.27)
				)
			)
		)
		(duplicate_pad_numbers_are_jumpers no)
		(fp_line
			(start -0.7874 -0.4064)
			(end 0.7874 -0.4064)
			(stroke
				(width 0.1524)
				(type default)
			)
			(layer "F.SilkS")
		)
		(fp_line
			(start -0.7874 0.4064)
			(end -0.7874 -0.4064)
			(stroke
				(width 0.1524)
				(type default)
			)
			(layer "F.SilkS")
		)
		(fp_line
			(start 0.7874 -0.4064)
			(end 0.7874 0.4064)
			(stroke
				(width 0.1524)
				(type default)
			)
			(layer "F.SilkS")
		)
		(fp_line
			(start 0.7874 0.4064)
			(end -0.7874 0.4064)
			(stroke
				(width 0.1524)
				(type default)
			)
			(layer "F.SilkS")
		)
		(fp_line
			(start -0.67945 -0.305054)
			(end -0.12065 -0.305054)
			(stroke
				(width 0.1)
				(type default)
			)
			(layer "F.Fab")
		)
		(fp_line
			(start -0.67945 0.3048)
			(end -0.67945 -0.305054)
			(stroke
				(width 0.1)
				(type default)
			)
			(layer "F.Fab")
		)
		(fp_line
			(start -0.12065 -0.305054)
			(end -0.12065 -0.2794)
			(stroke
				(width 0.1)
				(type default)
			)
			(layer "F.Fab")
		)
		(fp_line
			(start -0.12065 -0.2794)
			(end 0.12065 -0.2794)
			(stroke
				(width 0.1)
				(type default)
			)
			(layer "F.Fab")
		)
		(fp_line
			(start -0.12065 0.2794)
			(end -0.12065 0.3048)
			(stroke
				(width 0.1)
				(type default)
			)
			(layer "F.Fab")
		)
		(fp_line
			(start -0.12065 0.3048)
			(end -0.67945 0.3048)
			(stroke
				(width 0.1)
				(type default)
			)
			(layer "F.Fab")
		)
		(fp_line
			(start 0.120396 0.2794)
			(end -0.12065 0.2794)
			(stroke
				(width 0.1)
				(type default)
			)
			(layer "F.Fab")
		)
		(fp_line
			(start 0.120396 0.3048)
			(end 0.120396 0.2794)
			(stroke
				(width 0.1)
				(type default)
			)
			(layer "F.Fab")
		)
		(fp_line
			(start 0.12065 -0.3048)
			(end 0.67945 -0.3048)
			(stroke
				(width 0.1)
				(type default)
			)
			(layer "F.Fab")
		)
		(fp_line
			(start 0.12065 -0.2794)
			(end 0.12065 -0.3048)
			(stroke
				(width 0.1)
				(type default)
			)
			(layer "F.Fab")
		)
		(fp_line
			(start 0.67945 -0.3048)
			(end 0.67945 0.3048)
			(stroke
				(width 0.1)
				(type default)
			)
			(layer "F.Fab")
		)
		(fp_line
			(start 0.67945 0.3048)
			(end 0.120396 0.3048)
			(stroke
				(width 0.1)
				(type default)
			)
			(layer "F.Fab")
		)
		(pad "1" smd circle
			(at -0.40005 0)
			(size 0 0)
			(layers "F.Cu" "F.Mask" "F.Paste")
			(net "ADM1085_ENOUT")
		)
		(pad "2" smd circle
			(at 0.40005 0)
			(size 0 0)
			(layers "F.Cu" "F.Mask" "F.Paste")
			(net "GND")
		)
	)
	(footprint ""
		(layer "F.Cu")
		(at 142.922752 -311.156604 -90)
		(property "Reference" "R1325"
			(at 0 0 270)
			(layer "F.SilkS")
			(hide yes)
			(effects
				(font
					(size 1.27 1.27)
				)
			)
		)
		(property "Value" ""
			(at 0 0 270)
			(layer "F.Fab")
			(effects
				(font
					(size 1.27 1.27)
				)
			)
		)
		(duplicate_pad_numbers_are_jumpers no)
		(fp_line
			(start -0.7874 0.4064)
			(end -0.7874 -0.4064)
			(stroke
				(width 0.1524)
				(type default)
			)
			(layer "F.SilkS")
		)
		(fp_line
			(start 0.7874 0.4064)
			(end -0.7874 0.4064)
			(stroke
				(width 0.1524)
				(type default)
			)
			(layer "F.SilkS")
		)
		(fp_line
			(start -0.7874 -0.4064)
			(end 0.7874 -0.4064)
			(stroke
				(width 0.1524)
				(type default)
			)
			(layer "F.SilkS")
		)
		(fp_line
			(start 0.7874 -0.4064)
			(end 0.7874 0.4064)
			(stroke
				(width 0.1524)
				(type default)
			)
			(layer "F.SilkS")
		)
		(fp_line
			(start -0.67945 0.3048)
			(end -0.67945 -0.305054)
			(stroke
				(width 0.1)
				(type default)
			)
			(layer "F.Fab")
		)
		(fp_line
			(start -0.12065 0.3048)
			(end -0.67945 0.3048)
			(stroke
				(width 0.1)
				(type default)
			)
			(layer "F.Fab")
		)
		(fp_line
			(start 0.120396 0.3048)
			(end 0.120396 0.2794)
			(stroke
				(width 0.1)
				(type default)
			)
			(layer "F.Fab")
		)
		(fp_line
			(start 0.67945 0.3048)
			(end 0.120396 0.3048)
			(stroke
				(width 0.1)
				(type default)
			)
			(layer "F.Fab")
		)
		(fp_line
			(start -0.12065 0.2794)
			(end -0.12065 0.3048)
			(stroke
				(width 0.1)
				(type default)
			)
			(layer "F.Fab")
		)
		(fp_line
			(start 0.120396 0.2794)
			(end -0.12065 0.2794)
			(stroke
				(width 0.1)
				(type default)
			)
			(layer "F.Fab")
		)
		(fp_line
			(start -0.12065 -0.2794)
			(end 0.12065 -0.2794)
			(stroke
				(width 0.1)
				(type default)
			)
			(layer "F.Fab")
		)
		(fp_line
			(start 0.12065 -0.2794)
			(end 0.12065 -0.3048)
			(stroke
				(width 0.1)
				(type default)
			)
			(layer "F.Fab")
		)
		(fp_line
			(start 0.12065 -0.3048)
			(end 0.67945 -0.3048)
			(stroke
				(width 0.1)
				(type default)
			)
			(layer "F.Fab")
		)
		(fp_line
			(start 0.67945 -0.3048)
			(end 0.67945 0.3048)
			(stroke
				(width 0.1)
				(type default)
			)
			(layer "F.Fab")
		)
		(fp_line
			(start -0.67945 -0.305054)
			(end -0.12065 -0.305054)
			(stroke
				(width 0.1)
				(type default)
			)
			(layer "F.Fab")
		)
		(fp_line
			(start -0.12065 -0.305054)
			(end -0.12065 -0.2794)
			(stroke
				(width 0.1)
				(type default)
			)
			(layer "F.Fab")
		)
		(pad "1" smd circle
			(at -0.40005 0 270)
			(size 0 0)
			(layers "F.Cu" "F.Mask" "F.Paste")
			(net "PU_PEX1_TR_TCK")
		)
		(pad "2" smd circle
			(at 0.40005 0 270)
			(size 0 0)
			(layers "F.Cu" "F.Mask" "F.Paste")
			(net "P1V8_PEX")
		)
	)
)
